(kicad_pcb
	(version 20241229)
	(generator "pcbnew")
	(generator_version "9.0")
	(general
		(thickness 1.294)
		(legacy_teardrops no)
	)
	(paper "A3")
	(title_block
		(title "Kintex 410T devboard")
		(date "2024-04-03")
		(rev "1.1.2")
		(comment 9 "footprints 161-165 of 975")
	)
	(layers
		(0 "F.Cu" mixed)
		(4 "In1.Cu" power)
		(6 "In2.Cu" power)
		(8 "In3.Cu" mixed)
		(10 "In4.Cu" power)
		(12 "In5.Cu" mixed)
		(14 "In6.Cu" power)
		(16 "In7.Cu" mixed)
		(18 "In8.Cu" power)
		(2 "B.Cu" mixed)
		(9 "F.Adhes" user "F.Adhesive")
		(11 "B.Adhes" user "B.Adhesive")
		(13 "F.Paste" user)
		(15 "B.Paste" user)
		(5 "F.SilkS" user "F.Silkscreen")
		(7 "B.SilkS" user "B.Silkscreen")
		(1 "F.Mask" user)
		(3 "B.Mask" user)
		(17 "Dwgs.User" user "User.Drawings")
		(19 "Cmts.User" user "User.Comments")
		(21 "Eco1.User" user "User.Eco1")
		(23 "Eco2.User" user "User.Eco2")
		(25 "Edge.Cuts" user)
		(27 "Margin" user)
		(31 "F.CrtYd" user "F.Courtyard")
		(29 "B.CrtYd" user "B.Courtyard")
		(35 "F.Fab" user)
		(33 "B.Fab" user)
	)
	(footprint "antmicro-footprints:C_0402_1005Metric"
		(layer "F.Cu")
		(at 253.545 140.135 90)
		(descr "Capacitor SMD 0402")
		(tags "capacitor SMD 0402")
		(property "Reference" "C238"
			(at -1.515 1.255 90)
			(layer "F.SilkS")
			(effects
				(font
					(size 0.7 0.7)
					(thickness 0.15)
				)
				(justify left bottom)
			)
		)
		(property "Value" "C_100n_0402"
			(at 0 1.169 90)
			(layer "F.Fab")
			(effects
				(font
					(size 0.7 0.7)
					(thickness 0.15)
				)
				(justify left bottom)
			)
		)
		(property "Description" "SMD Multilayer Ceramic Capacitor, 0.1 µF, 50 V, 0402 [1005 Metric], ± 10%, X5R, GRM Series"
			(at 0 0 90)
			(layer "F.Fab")
			(hide yes)
			(effects
				(font
					(size 1.27 1.27)
					(thickness 0.15)
				)
			)
		)
		(property "Author" "Antmicro"
			(at 393.68 -113.41 0)
			(layer "F.Fab")
			(hide yes)
			(effects
				(font
					(size 1 1)
					(thickness 0.15)
				)
			)
		)
		(property "Dielectric" "X5R"
			(at 393.68 -113.41 0)
			(layer "F.Fab")
			(hide yes)
			(effects
				(font
					(size 1 1)
					(thickness 0.15)
				)
			)
		)
		(property "License" "Apache-2.0"
			(at 393.68 -113.41 0)
			(layer "F.Fab")
			(hide yes)
			(effects
				(font
					(size 1 1)
					(thickness 0.15)
				)
			)
		)
		(property "MPN" "GRM155R61H104KE14D"
			(at 393.68 -113.41 0)
			(layer "F.Fab")
			(hide yes)
			(effects
				(font
					(size 1 1)
					(thickness 0.15)
				)
			)
		)
		(property "Manufacturer" "Murata"
			(at 393.68 -113.41 0)
			(layer "F.Fab")
			(hide yes)
			(effects
				(font
					(size 1 1)
					(thickness 0.15)
				)
			)
		)
		(property "Val" "100n"
			(at 393.68 -113.41 0)
			(layer "F.Fab")
			(hide yes)
			(effects
				(font
					(size 1 1)
					(thickness 0.15)
				)
			)
		)
		(property "Voltage" "50V"
			(at 393.68 -113.41 0)
			(layer "F.Fab")
			(hide yes)
			(effects
				(font
					(size 1 1)
					(thickness 0.15)
				)
			)
		)
		(sheetname "USB PHY")
		(sheetfile "usb-phy.kicad_sch")
		(attr smd)
		(fp_rect
			(start -0.925 -0.47)
			(end 0.925 0.47)
			(stroke
				(width 0.05)
				(type default)
			)
			(fill no)
			(layer "F.CrtYd")
		)
		(fp_line
			(start 0.504 -0.25)
			(end 0.504 0.248)
			(stroke
				(width 0.15)
				(type solid)
			)
			(layer "F.Fab")
		)
		(fp_line
			(start -0.494 -0.25)
			(end 0.504 -0.25)
			(stroke
				(width 0.15)
				(type solid)
			)
			(layer "F.Fab")
		)
		(fp_line
			(start 0.504 0.248)
			(end -0.494 0.248)
			(stroke
				(width 0.15)
				(type solid)
			)
			(layer "F.Fab")
		)
		(fp_line
			(start -0.494 0.248)
			(end -0.494 -0.25)
			(stroke
				(width 0.15)
				(type solid)
			)
			(layer "F.Fab")
		)
		(pad "1" smd roundrect
			(at -0.48 0 90)
			(size 0.59 0.64)
			(layers "F.Cu" "F.Mask" "F.Paste")
			(roundrect_rratio 0.25)
			(net 1 "GND")
			(pintype "passive")
		)
		(pad "2" smd roundrect
			(at 0.48 0 90)
			(size 0.59 0.64)
			(layers "F.Cu" "F.Mask" "F.Paste")
			(roundrect_rratio 0.25)
			(net 712 "/USB PHY/FTDI_VCORE")
			(pintype "passive")
		)
	)
	(footprint "antmicro-footprints:DFN3538"
		(layer "F.Cu")
		(at 233 174.5 180)
		(property "Reference" "D5"
			(at 0.7 -3.3 0)
			(unlocked yes)
			(layer "F.SilkS")
			(effects
				(font
					(size 0.7 0.7)
					(thickness 0.15)
				)
				(justify left bottom)
			)
		)
		(property "Value" "CD-MMBL110S"
			(at 0 3.5 180)
			(unlocked yes)
			(layer "F.Fab")
			(effects
				(font
					(size 0.7 0.7)
					(thickness 0.15)
				)
				(justify left bottom)
			)
		)
		(property "Description" "TVS diode"
			(at 0 0 180)
			(layer "F.Fab")
			(hide yes)
			(effects
				(font
					(size 1.27 1.27)
					(thickness 0.15)
				)
			)
		)
		(property "Author" "Antmicro"
			(at 466 349 0)
			(layer "F.Fab")
			(hide yes)
			(effects
				(font
					(size 1 1)
					(thickness 0.15)
				)
			)
		)
		(property "License" "Apache-2.0"
			(at 466 349 0)
			(layer "F.Fab")
			(hide yes)
			(effects
				(font
					(size 1 1)
					(thickness 0.15)
				)
			)
		)
		(property "MPN" "CD-MMBL110S"
			(at 466 349 0)
			(layer "F.Fab")
			(hide yes)
			(effects
				(font
					(size 1 1)
					(thickness 0.15)
				)
			)
		)
		(property "Manufacturer" "Bourns"
			(at 466 349 0)
			(layer "F.Fab")
			(hide yes)
			(effects
				(font
					(size 1 1)
					(thickness 0.15)
				)
			)
		)
		(sheetname "Power supply")
		(sheetfile "power-supply.kicad_sch")
		(attr smd)
		(fp_line
			(start 1.8 -2)
			(end 1.8 2.05)
			(stroke
				(width 0.15)
				(type solid)
			)
			(layer "F.SilkS")
		)
		(fp_line
			(start 1.6 2.05)
			(end 1.8 2.05)
			(stroke
				(width 0.15)
				(type solid)
			)
			(layer "F.SilkS")
		)
		(fp_line
			(start 1.6 -2)
			(end 1.8 -2)
			(stroke
				(width 0.15)
				(type solid)
			)
			(layer "F.SilkS")
		)
		(fp_line
			(start 0.9 -2.301)
			(end 0.598 -2.301)
			(stroke
				(width 0.15)
				(type solid)
			)
			(layer "F.SilkS")
		)
		(fp_line
			(start 0.748 -2.452)
			(end 0.748 -2.15)
			(stroke
				(width 0.15)
				(type solid)
			)
			(layer "F.SilkS")
		)
		(fp_line
			(start -0.902 -2.25)
			(end -0.6 -2.25)
			(stroke
				(width 0.15)
				(type solid)
			)
			(layer "F.SilkS")
		)
		(fp_line
			(start -0.95 2.05)
			(end 0.95 2.05)
			(stroke
				(width 0.15)
				(type solid)
			)
			(layer "F.SilkS")
		)
		(fp_line
			(start -0.95 -2)
			(end 0.95 -2)
			(stroke
				(width 0.15)
				(type solid)
			)
			(layer "F.SilkS")
		)
		(fp_line
			(start -1.8 2.05)
			(end -1.6 2.05)
			(stroke
				(width 0.15)
				(type solid)
			)
			(layer "F.SilkS")
		)
		(fp_line
			(start -1.8 -1.5)
			(end -1.8 2.05)
			(stroke
				(width 0.15)
				(type solid)
			)
			(layer "F.SilkS")
		)
		(fp_rect
			(start -2.1 -2.6)
			(end 2.1 2.6)
			(stroke
				(width 0.05)
				(type solid)
			)
			(fill no)
			(layer "F.CrtYd")
		)
		(fp_line
			(start -1.051 -2)
			(end -1.801 -1.25)
			(stroke
				(width 0.15)
				(type solid)
			)
			(layer "F.Fab")
		)
		(fp_rect
			(start 1.8 2.048)
			(end -1.8 -2)
			(stroke
				(width 0.15)
				(type solid)
			)
			(fill no)
			(layer "F.Fab")
		)
		(fp_text user "~"
			(at -0.31 2.59 180)
			(unlocked yes)
			(layer "F.SilkS")
			(effects
				(font
					(size 0.7 0.7)
					(thickness 0.15)
				)
				(justify left bottom)
			)
		)
		(pad "1" smd roundrect
			(at -1.27 -1.85 270)
			(size 1.4 0.48)
			(layers "F.Cu" "F.Mask" "F.Paste")
			(roundrect_rratio 0.25)
			(net 756 "Net-(D4-Pad1)")
			(pinfunction "1")
			(pintype "output")
		)
		(pad "2" smd roundrect
			(at 1.27 -1.85 270)
			(size 1.4 0.48)
			(layers "F.Cu" "F.Mask" "F.Paste")
			(roundrect_rratio 0.25)
			(net 757 "Net-(D4-Pad2)")
			(pinfunction "2")
			(pintype "output")
		)
		(pad "3" smd roundrect
			(at -1.27 1.85 270)
			(size 1.4 0.48)
			(layers "F.Cu" "F.Mask" "F.Paste")
			(roundrect_rratio 0.25)
			(net 760 "/HDMI + Ethernet/POE_GBE.VC3")
			(pinfunction "3")
			(pintype "input")
		)
		(pad "4" smd roundrect
			(at 1.27 1.85 270)
			(size 1.4 0.48)
			(layers "F.Cu" "F.Mask" "F.Paste")
			(roundrect_rratio 0.25)
			(net 761 "/HDMI + Ethernet/POE_GBE.VC4")
			(pinfunction "4")
			(pintype "input")
		)
	)
	(footprint "antmicro-footprints:LED_0603_1608Metric_G"
		(layer "F.Cu")
		(at 266.6 137.8 180)
		(descr "LED SMD 0603 Green")
		(tags "LED SMD 0603 Green")
		(property "Reference" "D27"
			(at -3.4 0.75 0)
			(layer "F.SilkS")
			(effects
				(font
					(size 0.7 0.7)
					(thickness 0.15)
				)
				(justify right bottom)
			)
		)
		(property "Value" "LED_G_0603_KP-1608CGCK"
			(at 0 1.6 0)
			(layer "F.Fab")
			(effects
				(font
					(size 0.7 0.7)
					(thickness 0.15)
				)
				(justify right bottom)
			)
		)
		(property "Description" "LED, Green, SMD, 0603, 20 mA, 2.1 V, 570 nm"
			(at 0 0 180)
			(layer "F.Fab")
			(hide yes)
			(effects
				(font
					(size 1.27 1.27)
					(thickness 0.15)
				)
			)
		)
		(property "Author" "Antmicro"
			(at 533.2 275.6 0)
			(layer "F.Fab")
			(hide yes)
			(effects
				(font
					(size 1 1)
					(thickness 0.15)
				)
			)
		)
		(property "Color" "Green"
			(at 533.2 275.6 0)
			(layer "F.Fab")
			(hide yes)
			(effects
				(font
					(size 1 1)
					(thickness 0.15)
				)
			)
		)
		(property "License" "Apache-2.0"
			(at 533.2 275.6 0)
			(layer "F.Fab")
			(hide yes)
			(effects
				(font
					(size 1 1)
					(thickness 0.15)
				)
			)
		)
		(property "MPN" "KP-1608CGCK"
			(at 533.2 275.6 0)
			(layer "F.Fab")
			(hide yes)
			(effects
				(font
					(size 1 1)
					(thickness 0.15)
				)
			)
		)
		(property "Manufacturer" "Kingbright"
			(at 533.2 275.6 0)
			(layer "F.Fab")
			(hide yes)
			(effects
				(font
					(size 1 1)
					(thickness 0.15)
				)
			)
		)
		(sheetname "USB PHY")
		(sheetfile "usb-phy.kicad_sch")
		(attr smd)
		(fp_line
			(start 0.22 0.35)
			(end -0.22 0.35)
			(stroke
				(width 0.15)
				(type solid)
			)
			(layer "F.SilkS")
		)
		(fp_line
			(start 0.22 -0.35)
			(end -0.22 -0.35)
			(stroke
				(width 0.15)
				(type solid)
			)
			(layer "F.SilkS")
		)
		(fp_line
			(start 0.105328 0.201008)
			(end 0.105328 -0.198992)
			(stroke
				(width 0.1)
				(type solid)
			)
			(layer "F.SilkS")
		)
		(fp_line
			(start 0.105328 0.201008)
			(end -0.094672 0.001008)
			(stroke
				(width 0.1)
				(type solid)
			)
			(layer "F.SilkS")
		)
		(fp_line
			(start 0.105328 0.001008)
			(end 0.24 0.001)
			(stroke
				(width 0.1)
				(type solid)
			)
			(layer "F.SilkS")
		)
		(fp_line
			(start -0.094672 0.201008)
			(end -0.094672 -0.198992)
			(stroke
				(width 0.1)
				(type solid)
			)
			(layer "F.SilkS")
		)
		(fp_line
			(start -0.094672 0.001008)
			(end 0.105328 -0.198992)
			(stroke
				(width 0.1)
				(type solid)
			)
			(layer "F.SilkS")
		)
		(fp_line
			(start -0.094672 0.001008)
			(end -0.24 0.001008)
			(stroke
				(width 0.1)
				(type solid)
			)
			(layer "F.SilkS")
		)
		(fp_line
			(start -1.18 -0.319)
			(end -1.18 0.321)
			(stroke
				(width 0.15)
				(type solid)
			)
			(layer "F.SilkS")
		)
		(fp_rect
			(start 1.25 0.65)
			(end -1.25 -0.65)
			(stroke
				(width 0.05)
				(type solid)
			)
			(fill no)
			(layer "F.CrtYd")
		)
		(fp_line
			(start 0.599 0)
			(end 0.201 0)
			(stroke
				(width 0.15)
				(type solid)
			)
			(layer "F.Fab")
		)
		(fp_line
			(start 0.201 0.2)
			(end 0.201 0)
			(stroke
				(width 0.15)
				(type solid)
			)
			(layer "F.Fab")
		)
		(fp_line
			(start 0.201 0)
			(end 0.201 -0.202)
			(stroke
				(width 0.15)
				(type solid)
			)
			(layer "F.Fab")
		)
		(fp_line
			(start 0.201 -0.202)
			(end -0.101 0)
			(stroke
				(width 0.15)
				(type solid)
			)
			(layer "F.Fab")
		)
		(fp_line
			(start -0.101 0)
			(end 0.201 0.2)
			(stroke
				(width 0.15)
				(type solid)
			)
			(layer "F.Fab")
		)
		(fp_line
			(start -0.199 0.2)
			(end -0.199 0.1)
			(stroke
				(width 0.15)
				(type solid)
			)
			(layer "F.Fab")
		)
		(fp_line
			(start -0.199 0)
			(end -0.597 0)
			(stroke
				(width 0.15)
				(type solid)
			)
			(layer "F.Fab")
		)
		(fp_line
			(start -0.199 -0.202)
			(end -0.199 0.1)
			(stroke
				(width 0.15)
				(type solid)
			)
			(layer "F.Fab")
		)
		(fp_rect
			(start 0.848 0.4)
			(end -0.85 -0.402)
			(stroke
				(width 0.15)
				(type solid)
			)
			(fill no)
			(layer "F.Fab")
		)
		(pad "1" smd roundrect
			(at -0.7 0)
			(size 0.8 1)
			(layers "F.Cu" "F.Mask" "F.Paste")
			(roundrect_rratio 0.2)
			(net 1 "GND")
			(pinfunction "C")
			(pintype "passive")
		)
		(pad "2" smd roundrect
			(at 0.7 0)
			(size 0.8 1)
			(layers "F.Cu" "F.Mask" "F.Paste")
			(roundrect_rratio 0.2)
			(net 791 "Net-(D27-A)")
			(pinfunction "A")
			(pintype "passive")
		)
	)
	(footprint "antmicro-footprints:C_0402_1005Metric"
		(layer "F.Cu")
		(at 151.975 156.225)
		(descr "Capacitor SMD 0402")
		(tags "capacitor SMD 0402")
		(property "Reference" "C349"
			(at -1.625 1.225 0)
			(layer "F.SilkS")
			(effects
				(font
					(size 0.7 0.7)
					(thickness 0.15)
				)
				(justify left bottom)
			)
		)
		(property "Value" "C_10u_0402"
			(at 0 1.4 0)
			(layer "F.Fab")
			(effects
				(font
					(size 0.7 0.7)
					(thickness 0.15)
				)
				(justify left bottom)
			)
		)
		(property "Description" "SMD Multilayer Ceramic Capacitor, 10 µF, 6.3 V, 0402 [1005 Metric], ± 20%, X5R, CC Series"
			(at 0 0 0)
			(layer "F.Fab")
			(hide yes)
			(effects
				(font
					(size 1.27 1.27)
					(thickness 0.15)
				)
			)
		)
		(property "Author" "Antmicro"
			(at 0 0 0)
			(layer "F.Fab")
			(hide yes)
			(effects
				(font
					(size 1 1)
					(thickness 0.15)
				)
			)
		)
		(property "Dielectric" ""
			(at 0 0 0)
			(layer "F.Fab")
			(hide yes)
			(effects
				(font
					(size 1 1)
					(thickness 0.15)
				)
			)
		)
		(property "License" "Apache-2.0"
			(at 0 0 0)
			(layer "F.Fab")
			(hide yes)
			(effects
				(font
					(size 1 1)
					(thickness 0.15)
				)
			)
		)
		(property "MPN" "CC0402MRX5R5BB106"
			(at 0 0 0)
			(layer "F.Fab")
			(hide yes)
			(effects
				(font
					(size 1 1)
					(thickness 0.15)
				)
			)
		)
		(property "Manufacturer" "YAGEO"
			(at 0 0 0)
			(layer "F.Fab")
			(hide yes)
			(effects
				(font
					(size 1 1)
					(thickness 0.15)
				)
			)
		)
		(property "Val" "10u"
			(at 0 0 0)
			(layer "F.Fab")
			(hide yes)
			(effects
				(font
					(size 1 1)
					(thickness 0.15)
				)
			)
		)
		(property "Voltage" ""
			(at 0 0 0)
			(layer "F.Fab")
			(hide yes)
			(effects
				(font
					(size 1 1)
					(thickness 0.15)
				)
			)
		)
		(sheetname "DC-DC Converters")
		(sheetfile "dc-dc.kicad_sch")
		(attr smd)
		(fp_rect
			(start -0.925 -0.47)
			(end 0.925 0.47)
			(stroke
				(width 0.05)
				(type default)
			)
			(fill no)
			(layer "F.CrtYd")
		)
		(fp_line
			(start -0.494 -0.25)
			(end 0.504 -0.25)
			(stroke
				(width 0.15)
				(type solid)
			)
			(layer "F.Fab")
		)
		(fp_line
			(start -0.494 0.248)
			(end -0.494 -0.25)
			(stroke
				(width 0.15)
				(type solid)
			)
			(layer "F.Fab")
		)
		(fp_line
			(start 0.504 -0.25)
			(end 0.504 0.248)
			(stroke
				(width 0.15)
				(type solid)
			)
			(layer "F.Fab")
		)
		(fp_line
			(start 0.504 0.248)
			(end -0.494 0.248)
			(stroke
				(width 0.15)
				(type solid)
			)
			(layer "F.Fab")
		)
		(pad "1" smd roundrect
			(at -0.48 0)
			(size 0.59 0.64)
			(layers "F.Cu" "F.Mask" "F.Paste")
			(roundrect_rratio 0.25)
			(net 1 "GND")
			(pintype "passive")
		)
		(pad "2" smd roundrect
			(at 0.48 0)
			(size 0.59 0.64)
			(layers "F.Cu" "F.Mask" "F.Paste")
			(roundrect_rratio 0.25)
			(net 24 "+3V3")
			(pintype "passive")
		)
	)
	(footprint "antmicro-footprints:R_0402_1005Metric"
		(layer "F.Cu")
		(at 238.8 127.8 90)
		(descr "Resistor SMD 0402")
		(tags "resistor SMD 0402")
		(property "Reference" "R175"
			(at 0.75 0.375 90)
			(layer "F.SilkS")
			(effects
				(font
					(size 0.7 0.7)
					(thickness 0.15)
				)
				(justify left bottom)
			)
		)
		(property "Value" "R_47k_0402"
			(at 0 1.4 90)
			(layer "F.Fab")
			(effects
				(font
					(size 0.7 0.7)
					(thickness 0.15)
				)
				(justify left bottom)
			)
		)
		(property "Description" "SMD Chip Resistor, 47 kohm, ± 1%, 62.5 mW, 0402 [1005 Metric], Thick Film, General Purpose"
			(at 0 0 90)
			(layer "F.Fab")
			(hide yes)
			(effects
				(font
					(size 1.27 1.27)
					(thickness 0.15)
				)
			)
		)
		(property "Author" "Antmicro"
			(at 366.6 -111 0)
			(layer "F.Fab")
			(hide yes)
			(effects
				(font
					(size 1 1)
					(thickness 0.15)
				)
			)
		)
		(property "License" "Apache-2.0"
			(at 366.6 -111 0)
			(layer "F.Fab")
			(hide yes)
			(effects
				(font
					(size 1 1)
					(thickness 0.15)
				)
			)
		)
		(property "MPN" "CR0402-FX-4702GLF"
			(at 366.6 -111 0)
			(layer "F.Fab")
			(hide yes)
			(effects
				(font
					(size 1 1)
					(thickness 0.15)
				)
			)
		)
		(property "Manufacturer" "Bourns"
			(at 366.6 -111 0)
			(layer "F.Fab")
			(hide yes)
			(effects
				(font
					(size 1 1)
					(thickness 0.15)
				)
			)
		)
		(property "Tolerance" "1%"
			(at 366.6 -111 0)
			(layer "F.Fab")
			(hide yes)
			(effects
				(font
					(size 1 1)
					(thickness 0.15)
				)
			)
		)
		(property "Val" "47k"
			(at 366.6 -111 0)
			(layer "F.Fab")
			(hide yes)
			(effects
				(font
					(size 1 1)
					(thickness 0.15)
				)
			)
		)
		(sheetname "USB PHY")
		(sheetfile "usb-phy.kicad_sch")
		(attr smd)
		(fp_rect
			(start -0.925 -0.47)
			(end 0.925 0.47)
			(stroke
				(width 0.05)
				(type default)
			)
			(fill no)
			(layer "F.CrtYd")
		)
		(fp_rect
			(start -0.5 -0.25)
			(end 0.5 0.25)
			(stroke
				(width 0.15)
				(type solid)
			)
			(fill no)
			(layer "F.Fab")
		)
		(pad "1" smd roundrect
			(at -0.48 0 90)
			(size 0.59 0.64)
			(layers "F.Cu" "F.Mask" "F.Paste")
			(roundrect_rratio 0.25)
			(net 799 "FTDI_DIS")
			(pintype "passive")
		)
		(pad "2" smd roundrect
			(at 0.48 0 90)
			(size 0.59 0.64)
			(layers "F.Cu" "F.Mask" "F.Paste")
			(roundrect_rratio 0.25)
			(net 24 "+3V3")
			(pintype "passive")
		)
	)
)
